# T6G (Grand Teton) — schematic netlist excerpt (pin names and nets, part order shuffled) for the footprints in the layout excerpt that follows; sources: Cadence DE-HDL packaged netlist, KiCad conversion of 04192023_DAF0TMB3IC0_F0TG_MB_C_brd_V02_OCP.brd

R224  Q_RES  33 5% CHIP  pkg 0402LF  page 81 : A = PVDD33_S5_EN ; B = FM_PVDD33_S5_EN
PR430  Q_RES  2.2 1% CHIP  pkg 0402LF  page 196 : A = PVDDCR_CPU0_P0_PVCC ; B = PVDDCR_CPU0_P0_VCC6

(kicad_pcb
	(version 20260206)
	(generator "pcbnew")
	(generator_version "10.0")
	(general
		(thickness 1.6)
		(legacy_teardrops no)
	)
	(paper "A4")
	(title_block
		(title "04192023_DAF0TMB3IC0_F0TG_MB_C_brd_V02_OCP.brd")
		(comment 1 "Grand Teton / footprints 5668-5669 of 8354")
	)
	(layers
		(0 "F.Cu" signal "TOP")
		(4 "In1.Cu" signal "GND")
		(6 "In2.Cu" signal "IN1")
		(8 "In3.Cu" signal "GND1")
		(10 "In4.Cu" signal "IN2")
		(12 "In5.Cu" signal "GND2")
		(14 "In6.Cu" signal "IN3")
		(16 "In7.Cu" signal "GND3")
		(18 "In8.Cu" signal "VCC")
		(20 "In9.Cu" signal "VCC1")
		(22 "In10.Cu" signal "GND4")
		(24 "In11.Cu" signal "IN4")
		(26 "In12.Cu" signal "GND5")
		(28 "In13.Cu" signal "IN5")
		(30 "In14.Cu" signal "GND6")
		(32 "In15.Cu" signal "IN6")
		(34 "In16.Cu" signal "GND7")
		(2 "B.Cu" signal "BOTTOM")
		(9 "F.Adhes" user "F.Adhesive")
		(11 "B.Adhes" user "B.Adhesive")
		(13 "F.Paste" user "Package Geometry/Pastemask Top")
		(15 "B.Paste" user "Package Geometry/Pastemask Bottom")
		(5 "F.SilkS" user "Ref Des/Silkscreen Top")
		(7 "B.SilkS" user "Ref Des/Silkscreen Bottom")
		(1 "F.Mask" user "Board Geometry/Soldermask Top")
		(3 "B.Mask" user "Board Geometry/Soldermask Bottom")
		(17 "Dwgs.User" user "User.Drawings")
		(19 "Cmts.User" user "User.Comments")
		(21 "Eco1.User" user "User.Eco1")
		(23 "Eco2.User" user "User.Eco2")
		(25 "Edge.Cuts" user "Board Geometry/Outline")
		(27 "Margin" user)
		(31 "F.CrtYd" user "Package Geometry/Place Bound Top")
		(29 "B.CrtYd" user "Package Geometry/Place Bound Bottom")
		(35 "F.Fab" user "Ref Des/Assembly Top")
		(33 "B.Fab" user "Ref Des/Assembly Bottom")
	)
	(footprint ""
		(layer "B.Cu")
		(at 350.03867 -160.080198 90)
		(property "Reference" "PR430"
			(at 0 0 90)
			(layer "B.SilkS")
			(hide yes)
			(effects
				(font
					(size 1.27 1.27)
				)
				(justify mirror)
			)
		)
		(property "Value" ""
			(at 0 0 90)
			(layer "B.Fab")
			(effects
				(font
					(size 1.27 1.27)
				)
				(justify mirror)
			)
		)
		(duplicate_pad_numbers_are_jumpers no)
		(fp_line
			(start 0.7874 -0.4064)
			(end -0.7874 -0.4064)
			(stroke
				(width 0.1524)
				(type default)
			)
			(layer "B.SilkS")
		)
		(fp_line
			(start -0.7874 -0.4064)
			(end -0.7874 0.4064)
			(stroke
				(width 0.1524)
				(type default)
			)
			(layer "B.SilkS")
		)
		(fp_line
			(start 0.7874 0.4064)
			(end 0.7874 -0.4064)
			(stroke
				(width 0.1524)
				(type default)
			)
			(layer "B.SilkS")
		)
		(fp_line
			(start -0.7874 0.4064)
			(end 0.7874 0.4064)
			(stroke
				(width 0.1524)
				(type default)
			)
			(layer "B.SilkS")
		)
		(fp_line
			(start 0.67945 -0.305054)
			(end 0.12065 -0.305054)
			(stroke
				(width 0.1)
				(type default)
			)
			(layer "B.Fab")
		)
		(fp_line
			(start 0.12065 -0.305054)
			(end 0.12065 -0.2794)
			(stroke
				(width 0.1)
				(type default)
			)
			(layer "B.Fab")
		)
		(fp_line
			(start -0.12065 -0.3048)
			(end -0.67945 -0.3048)
			(stroke
				(width 0.1)
				(type default)
			)
			(layer "B.Fab")
		)
		(fp_line
			(start -0.67945 -0.3048)
			(end -0.67945 0.3048)
			(stroke
				(width 0.1)
				(type default)
			)
			(layer "B.Fab")
		)
		(fp_line
			(start 0.12065 -0.2794)
			(end -0.12065 -0.2794)
			(stroke
				(width 0.1)
				(type default)
			)
			(layer "B.Fab")
		)
		(fp_line
			(start -0.12065 -0.2794)
			(end -0.12065 -0.3048)
			(stroke
				(width 0.1)
				(type default)
			)
			(layer "B.Fab")
		)
		(fp_line
			(start 0.12065 0.2794)
			(end 0.12065 0.3048)
			(stroke
				(width 0.1)
				(type default)
			)
			(layer "B.Fab")
		)
		(fp_line
			(start -0.120396 0.2794)
			(end 0.12065 0.2794)
			(stroke
				(width 0.1)
				(type default)
			)
			(layer "B.Fab")
		)
		(fp_line
			(start 0.67945 0.3048)
			(end 0.67945 -0.305054)
			(stroke
				(width 0.1)
				(type default)
			)
			(layer "B.Fab")
		)
		(fp_line
			(start 0.12065 0.3048)
			(end 0.67945 0.3048)
			(stroke
				(width 0.1)
				(type default)
			)
			(layer "B.Fab")
		)
		(fp_line
			(start -0.120396 0.3048)
			(end -0.120396 0.2794)
			(stroke
				(width 0.1)
				(type default)
			)
			(layer "B.Fab")
		)
		(fp_line
			(start -0.67945 0.3048)
			(end -0.120396 0.3048)
			(stroke
				(width 0.1)
				(type default)
			)
			(layer "B.Fab")
		)
		(pad "1" smd circle
			(at 0.40005 0 270)
			(size 0 0)
			(layers "B.Cu" "B.Mask" "B.Paste")
			(net "PVDDCR_CPU0_P0_PVCC")
		)
		(pad "2" smd circle
			(at -0.40005 0 270)
			(size 0 0)
			(layers "B.Cu" "B.Mask" "B.Paste")
			(net "PVDDCR_CPU0_P0_VCC6")
		)
	)
	(footprint ""
		(layer "B.Cu")
		(at 198.438008 -111.380016)
		(property "Reference" "R224"
			(at 0 0 0)
			(layer "B.SilkS")
			(hide yes)
			(effects
				(font
					(size 1.27 1.27)
				)
				(justify mirror)
			)
		)
		(property "Value" ""
			(at 0 0 0)
			(layer "B.Fab")
			(effects
				(font
					(size 1.27 1.27)
				)
				(justify mirror)
			)
		)
		(duplicate_pad_numbers_are_jumpers no)
		(fp_line
			(start -0.7874 -0.4064)
			(end -0.7874 0.4064)
			(stroke
				(width 0.1524)
				(type default)
			)
			(layer "B.SilkS")
		)
		(fp_line
			(start -0.7874 0.4064)
			(end 0.7874 0.4064)
			(stroke
				(width 0.1524)
				(type default)
			)
			(layer "B.SilkS")
		)
		(fp_line
			(start 0.7874 -0.4064)
			(end -0.7874 -0.4064)
			(stroke
				(width 0.1524)
				(type default)
			)
			(layer "B.SilkS")
		)
		(fp_line
			(start 0.7874 0.4064)
			(end 0.7874 -0.4064)
			(stroke
				(width 0.1524)
				(type default)
			)
			(layer "B.SilkS")
		)
		(fp_line
			(start -0.67945 -0.3048)
			(end -0.67945 0.3048)
			(stroke
				(width 0.1)
				(type default)
			)
			(layer "B.Fab")
		)
		(fp_line
			(start -0.67945 0.3048)
			(end -0.120396 0.3048)
			(stroke
				(width 0.1)
				(type default)
			)
			(layer "B.Fab")
		)
		(fp_line
			(start -0.12065 -0.3048)
			(end -0.67945 -0.3048)
			(stroke
				(width 0.1)
				(type default)
			)
			(layer "B.Fab")
		)
		(fp_line
			(start -0.12065 -0.2794)
			(end -0.12065 -0.3048)
			(stroke
				(width 0.1)
				(type default)
			)
			(layer "B.Fab")
		)
		(fp_line
			(start -0.120396 0.2794)
			(end 0.12065 0.2794)
			(stroke
				(width 0.1)
				(type default)
			)
			(layer "B.Fab")
		)
		(fp_line
			(start -0.120396 0.3048)
			(end -0.120396 0.2794)
			(stroke
				(width 0.1)
				(type default)
			)
			(layer "B.Fab")
		)
		(fp_line
			(start 0.12065 -0.305054)
			(end 0.12065 -0.2794)
			(stroke
				(width 0.1)
				(type default)
			)
			(layer "B.Fab")
		)
		(fp_line
			(start 0.12065 -0.2794)
			(end -0.12065 -0.2794)
			(stroke
				(width 0.1)
				(type default)
			)
			(layer "B.Fab")
		)
		(fp_line
			(start 0.12065 0.2794)
			(end 0.12065 0.3048)
			(stroke
				(width 0.1)
				(type default)
			)
			(layer "B.Fab")
		)
		(fp_line
			(start 0.12065 0.3048)
			(end 0.67945 0.3048)
			(stroke
				(width 0.1)
				(type default)
			)
			(layer "B.Fab")
		)
		(fp_line
			(start 0.67945 -0.305054)
			(end 0.12065 -0.305054)
			(stroke
				(width 0.1)
				(type default)
			)
			(layer "B.Fab")
		)
		(fp_line
			(start 0.67945 0.3048)
			(end 0.67945 -0.305054)
			(stroke
				(width 0.1)
				(type default)
			)
			(layer "B.Fab")
		)
		(pad "1" smd circle
			(at 0.40005 0 180)
			(size 0 0)
			(layers "B.Cu" "B.Mask" "B.Paste")
			(net "PVDD33_S5_EN")
		)
		(pad "2" smd circle
			(at -0.40005 0 180)
			(size 0 0)
			(layers "B.Cu" "B.Mask" "B.Paste")
			(net "FM_PVDD33_S5_EN")
		)
	)
)
